(kicad_pcb
	(version 20260206)
	(generator "pcbnew")
	(generator_version "10.0")
	(general
		(thickness 1.6)
		(legacy_teardrops no)
	)
	(paper "A4")
	(title_block
		(title "baseboard — 13948-1b.1110WZS1818.brd")
		(comment 1 "Honey Badger (Wiwynn) / footprints 2300-2309 of 2523")
	)
	(layers
		(0 "F.Cu" signal "TOP")
		(4 "In1.Cu" signal "L2GND")
		(6 "In2.Cu" signal "L3")
		(8 "In3.Cu" signal "L4VCC")
		(10 "In4.Cu" signal "L5VCC")
		(12 "In5.Cu" signal "L6")
		(14 "In6.Cu" signal "L7GND")
		(2 "B.Cu" signal "BOTTOM")
		(9 "F.Adhes" user "F.Adhesive")
		(11 "B.Adhes" user "B.Adhesive")
		(13 "F.Paste" user "Package Geometry/Pastemask Top")
		(15 "B.Paste" user "Package Geometry/Pastemask Bottom")
		(5 "F.SilkS" user "Ref Des/Silkscreen Top")
		(7 "B.SilkS" user "Ref Des/Silkscreen Bottom")
		(1 "F.Mask" user "Board Geometry/Soldermask Top")
		(3 "B.Mask" user "Board Geometry/Soldermask Bottom")
		(17 "Dwgs.User" user "User.Drawings")
		(19 "Cmts.User" user "User.Comments")
		(21 "Eco1.User" user "User.Eco1")
		(23 "Eco2.User" user "User.Eco2")
		(25 "Edge.Cuts" user "Board Geometry/Outline")
		(27 "Margin" user)
		(31 "F.CrtYd" user "Package Geometry/Place Bound Top")
		(29 "B.CrtYd" user "Package Geometry/Place Bound Bottom")
		(35 "F.Fab" user "Ref Des/Assembly Top")
		(33 "B.Fab" user "Ref Des/Assembly Bottom")
	)
	(footprint ""
		(layer "B.Cu")
		(at 105.137966 -33.655 180)
		(property "Reference" "SC951"
			(at 0 0 0)
			(layer "B.SilkS")
			(hide yes)
			(effects
				(font
					(size 1.27 1.27)
				)
				(justify mirror)
			)
		)
		(property "Value" "SCD1U6D3V1KX-GP"
			(at 2.8321 -1.7399 180)
			(unlocked yes)
			(layer "B.Fab")
			(hide yes)
			(effects
				(font
					(size 1.016 1.016)
					(thickness 0.1524)
				)
				(justify mirror)
			)
		)
		(property "Device Type" "C0201H13"
			(at 2.8321 -3.2639 180)
			(unlocked yes)
			(layer "B.Fab")
			(hide yes)
			(effects
				(font
					(size 1.016 1.016)
					(thickness 0.1524)
				)
				(justify mirror)
			)
		)
		(duplicate_pad_numbers_are_jumpers no)
		(fp_rect
			(start 0.2794 0.6477)
			(end -0.2794 -0.6477)
			(stroke
				(width 0)
				(type default)
			)
			(fill no)
			(layer "B.CrtYd")
		)
		(fp_rect
			(start 0.2794 0.6477)
			(end -0.2794 -0.6477)
			(stroke
				(width 0)
				(type default)
			)
			(fill no)
			(layer "B.Fab")
		)
		(pad "1" smd custom
			(at 0 -0.2794)
			(size 0.0762 0.0762)
			(layers "B.Cu" "B.Mask" "B.Paste")
			(net "PCE_AVDD")
			(options
				(clearance outline)
				(anchor circle)
			)
			(primitives
				(gr_poly
					(pts
						(arc
							(start 0.1524 0.127)
							(mid 0.137521 0.162921)
							(end 0.1016 0.1778)
						)
						(arc
							(start -0.1016 0.1778)
							(mid -0.137521 0.162921)
							(end -0.1524 0.127)
						)
						(arc
							(start -0.1524 -0.127)
							(mid -0.137521 -0.162921)
							(end -0.1016 -0.1778)
						)
						(arc
							(start 0.1016 -0.1778)
							(mid 0.137521 -0.162921)
							(end 0.1524 -0.127)
						)
					)
					(width 0)
					(fill yes)
				)
			)
		)
		(pad "2" smd custom
			(at 0 0.2794)
			(size 0.0762 0.0762)
			(layers "B.Cu" "B.Mask" "B.Paste")
			(net "GND")
			(options
				(clearance outline)
				(anchor circle)
			)
			(primitives
				(gr_poly
					(pts
						(arc
							(start 0.1524 0.127)
							(mid 0.137521 0.162921)
							(end 0.1016 0.1778)
						)
						(arc
							(start -0.1016 0.1778)
							(mid -0.137521 0.162921)
							(end -0.1524 0.127)
						)
						(arc
							(start -0.1524 -0.127)
							(mid -0.137521 -0.162921)
							(end -0.1016 -0.1778)
						)
						(arc
							(start 0.1016 -0.1778)
							(mid 0.137521 -0.162921)
							(end 0.1524 -0.127)
						)
					)
					(width 0)
					(fill yes)
				)
			)
		)
	)
	(footprint ""
		(layer "B.Cu")
		(at 111.38916 -30.226)
		(property "Reference" "STP78"
			(at 0 0 0)
			(layer "B.SilkS")
			(hide yes)
			(effects
				(font
					(size 1.27 1.27)
				)
				(justify mirror)
			)
		)
		(property "Value" "TPAD28"
			(at -0.0127 -1.8034 0)
			(unlocked yes)
			(layer "B.Fab")
			(hide yes)
			(effects
				(font
					(size 1.016 1.016)
					(thickness 0.1524)
				)
				(justify mirror)
			)
		)
		(property "Device Type" "TPAD28"
			(at -0.0127 -3.3274 0)
			(unlocked yes)
			(layer "B.Fab")
			(hide yes)
			(effects
				(font
					(size 1.016 1.016)
					(thickness 0.1524)
				)
				(justify mirror)
			)
		)
		(duplicate_pad_numbers_are_jumpers no)
		(fp_poly
			(pts
				(arc
					(start 0.3556 0)
					(mid -0.3556 0)
					(end 0.3556 0)
				)
			)
			(stroke
				(width 0)
				(type default)
			)
			(fill no)
			(layer "B.CrtYd")
		)
		(fp_poly
			(pts
				(arc
					(start 0.6096 0)
					(mid -0.6096 0)
					(end 0.6096 0)
				)
			)
			(stroke
				(width 0)
				(type default)
			)
			(fill no)
			(layer "B.Fab")
		)
		(pad "1" smd circle
			(at 0 0 180)
			(size 0.7112 0.7112)
			(layers "B.Cu" "B.Mask" "B.Paste")
			(net "IOC_GPIO_1")
		)
	)
	(footprint ""
		(layer "B.Cu")
		(at 121.29897 -87.503 -90)
		(property "Reference" "SC1181"
			(at 0 0 90)
			(layer "B.SilkS")
			(hide yes)
			(effects
				(font
					(size 1.27 1.27)
				)
				(justify mirror)
			)
		)
		(property "Value" "SCD1U6D3V1KX-GP"
			(at 2.8321 -1.7399 270)
			(unlocked yes)
			(layer "B.Fab")
			(hide yes)
			(effects
				(font
					(size 1.016 1.016)
					(thickness 0.1524)
				)
				(justify mirror)
			)
		)
		(property "Device Type" "C0201H13"
			(at 2.8321 -3.2639 270)
			(unlocked yes)
			(layer "B.Fab")
			(hide yes)
			(effects
				(font
					(size 1.016 1.016)
					(thickness 0.1524)
				)
				(justify mirror)
			)
		)
		(duplicate_pad_numbers_are_jumpers no)
		(fp_rect
			(start 0.2794 0.6477)
			(end -0.2794 -0.6477)
			(stroke
				(width 0)
				(type default)
			)
			(fill no)
			(layer "B.CrtYd")
		)
		(fp_rect
			(start 0.2794 0.6477)
			(end -0.2794 -0.6477)
			(stroke
				(width 0)
				(type default)
			)
			(fill no)
			(layer "B.Fab")
		)
		(pad "1" smd custom
			(at 0 -0.2794 90)
			(size 0.0762 0.0762)
			(layers "B.Cu" "B.Mask" "B.Paste")
			(net "GB_VDDA")
			(options
				(clearance outline)
				(anchor circle)
			)
			(primitives
				(gr_poly
					(pts
						(arc
							(start 0.1524 0.127)
							(mid 0.137521 0.162921)
							(end 0.1016 0.1778)
						)
						(arc
							(start -0.1016 0.1778)
							(mid -0.137521 0.162921)
							(end -0.1524 0.127)
						)
						(arc
							(start -0.1524 -0.127)
							(mid -0.137521 -0.162921)
							(end -0.1016 -0.1778)
						)
						(arc
							(start 0.1016 -0.1778)
							(mid 0.137521 -0.162921)
							(end 0.1524 -0.127)
						)
					)
					(width 0)
					(fill yes)
				)
			)
		)
		(pad "2" smd custom
			(at 0 0.2794 90)
			(size 0.0762 0.0762)
			(layers "B.Cu" "B.Mask" "B.Paste")
			(net "GND")
			(options
				(clearance outline)
				(anchor circle)
			)
			(primitives
				(gr_poly
					(pts
						(arc
							(start 0.1524 0.127)
							(mid 0.137521 0.162921)
							(end 0.1016 0.1778)
						)
						(arc
							(start -0.1016 0.1778)
							(mid -0.137521 0.162921)
							(end -0.1524 0.127)
						)
						(arc
							(start -0.1524 -0.127)
							(mid -0.137521 -0.162921)
							(end -0.1016 -0.1778)
						)
						(arc
							(start 0.1016 -0.1778)
							(mid 0.137521 -0.162921)
							(end 0.1524 -0.127)
						)
					)
					(width 0)
					(fill yes)
				)
			)
		)
	)
	(footprint ""
		(layer "B.Cu")
		(at 340.995 -100.203 90)
		(property "Reference" "PC14"
			(at 0 0 90)
			(layer "B.SilkS")
			(hide yes)
			(effects
				(font
					(size 1.27 1.27)
				)
				(justify mirror)
			)
		)
		(property "Value" "SCD1U50V3KX-GP"
			(at 0 -2.8194 90)
			(unlocked yes)
			(layer "B.Fab")
			(hide yes)
			(effects
				(font
					(size 1.016 1.016)
					(thickness 0.1524)
				)
				(justify mirror)
			)
		)
		(property "Device Type" "C603H36"
			(at 0 -4.3434 90)
			(unlocked yes)
			(layer "B.Fab")
			(hide yes)
			(effects
				(font
					(size 1.016 1.016)
					(thickness 0.1524)
				)
				(justify mirror)
			)
		)
		(duplicate_pad_numbers_are_jumpers no)
		(fp_line
			(start -0.508 0)
			(end 0.508 0)
			(stroke
				(width 0.2032)
				(type default)
			)
			(layer "B.SilkS")
		)
		(fp_rect
			(start 0.5842 1.3335)
			(end -0.5842 -1.3335)
			(stroke
				(width 0)
				(type default)
			)
			(fill no)
			(layer "B.CrtYd")
		)
		(fp_rect
			(start 0.5842 1.3335)
			(end -0.5842 -1.3335)
			(stroke
				(width 0)
				(type default)
			)
			(fill no)
			(layer "B.Fab")
		)
		(pad "1" smd custom
			(at 0 -0.762 270)
			(size 0.2159 0.2159)
			(layers "B.Cu" "B.Mask" "B.Paste")
			(net "P5V_STBY_VFB_R")
			(options
				(clearance outline)
				(anchor circle)
			)
			(primitives
				(gr_poly
					(pts
						(arc
							(start -0.3302 0.4318)
							(mid -0.402042 0.402042)
							(end -0.4318 0.3302)
						)
						(arc
							(start -0.4318 -0.3302)
							(mid -0.402042 -0.402042)
							(end -0.3302 -0.4318)
						)
						(arc
							(start 0.3302 -0.4318)
							(mid 0.402042 -0.402042)
							(end 0.4318 -0.3302)
						)
						(arc
							(start 0.4318 0.3302)
							(mid 0.402042 0.402042)
							(end 0.3302 0.4318)
						)
					)
					(width 0)
					(fill yes)
				)
			)
		)
		(pad "2" smd custom
			(at 0 0.762 270)
			(size 0.2159 0.2159)
			(layers "B.Cu" "B.Mask" "B.Paste")
			(net "P5V_STBY")
			(options
				(clearance outline)
				(anchor circle)
			)
			(primitives
				(gr_poly
					(pts
						(arc
							(start -0.3302 0.4318)
							(mid -0.402042 0.402042)
							(end -0.4318 0.3302)
						)
						(arc
							(start -0.4318 -0.3302)
							(mid -0.402042 -0.402042)
							(end -0.3302 -0.4318)
						)
						(arc
							(start 0.3302 -0.4318)
							(mid 0.402042 -0.402042)
							(end 0.4318 -0.3302)
						)
						(arc
							(start 0.4318 0.3302)
							(mid 0.402042 0.402042)
							(end 0.3302 0.4318)
						)
					)
					(width 0)
					(fill yes)
				)
			)
		)
	)
	(footprint ""
		(layer "B.Cu")
		(at 110.954566 -38.53434 -90)
		(property "Reference" "SC986"
			(at 0 0 90)
			(layer "B.SilkS")
			(hide yes)
			(effects
				(font
					(size 1.27 1.27)
				)
				(justify mirror)
			)
		)
		(property "Value" "SCD1U16V2KX-3GP"
			(at -1.1811 -2.7051 270)
			(unlocked yes)
			(layer "B.Fab")
			(hide yes)
			(effects
				(font
					(size 1.016 1.016)
					(thickness 0.1524)
				)
				(justify mirror)
			)
		)
		(property "Device Type" "C402H22"
			(at -1.1811 -4.2291 270)
			(unlocked yes)
			(layer "B.Fab")
			(hide yes)
			(effects
				(font
					(size 1.016 1.016)
					(thickness 0.1524)
				)
				(justify mirror)
			)
		)
		(duplicate_pad_numbers_are_jumpers no)
		(fp_rect
			(start 0.4318 0.9525)
			(end -0.4318 -0.9525)
			(stroke
				(width 0)
				(type default)
			)
			(fill no)
			(layer "B.CrtYd")
		)
		(fp_rect
			(start 0.4318 0.9525)
			(end -0.4318 -0.9525)
			(stroke
				(width 0)
				(type default)
			)
			(fill no)
			(layer "B.Fab")
		)
		(pad "1" smd custom
			(at 0 -0.4445 90)
			(size 0.1524 0.1524)
			(layers "B.Cu" "B.Mask" "B.Paste")
			(net "P1V8_C")
			(options
				(clearance outline)
				(anchor circle)
			)
			(primitives
				(gr_poly
					(pts
						(arc
							(start 0.3048 0.2032)
							(mid 0.275042 0.275042)
							(end 0.2032 0.3048)
						)
						(arc
							(start -0.2032 0.3048)
							(mid -0.275042 0.275042)
							(end -0.3048 0.2032)
						)
						(arc
							(start -0.3048 -0.2032)
							(mid -0.275042 -0.275042)
							(end -0.2032 -0.3048)
						)
						(arc
							(start 0.2032 -0.3048)
							(mid 0.275042 -0.275042)
							(end 0.3048 -0.2032)
						)
					)
					(width 0)
					(fill yes)
				)
			)
		)
		(pad "2" smd custom
			(at 0 0.4445 90)
			(size 0.1524 0.1524)
			(layers "B.Cu" "B.Mask" "B.Paste")
			(net "GND")
			(options
				(clearance outline)
				(anchor circle)
			)
			(primitives
				(gr_poly
					(pts
						(arc
							(start 0.3048 0.2032)
							(mid 0.275042 0.275042)
							(end 0.2032 0.3048)
						)
						(arc
							(start -0.2032 0.3048)
							(mid -0.275042 0.275042)
							(end -0.3048 0.2032)
						)
						(arc
							(start -0.3048 -0.2032)
							(mid -0.275042 -0.275042)
							(end -0.2032 -0.3048)
						)
						(arc
							(start 0.2032 -0.3048)
							(mid 0.275042 -0.275042)
							(end 0.3048 -0.2032)
						)
					)
					(width 0)
					(fill yes)
				)
			)
		)
	)
	(footprint ""
		(layer "B.Cu")
		(at 158.42996 -107.239054 90)
		(property "Reference" "SC1243"
			(at 0 0 90)
			(layer "B.SilkS")
			(hide yes)
			(effects
				(font
					(size 1.27 1.27)
				)
				(justify mirror)
			)
		)
		(property "Value" "SCD1U6D3V1KX-GP"
			(at 2.8321 -1.7399 90)
			(unlocked yes)
			(layer "B.Fab")
			(hide yes)
			(effects
				(font
					(size 1.016 1.016)
					(thickness 0.1524)
				)
				(justify mirror)
			)
		)
		(property "Device Type" "C0201H13"
			(at 2.8321 -3.2639 90)
			(unlocked yes)
			(layer "B.Fab")
			(hide yes)
			(effects
				(font
					(size 1.016 1.016)
					(thickness 0.1524)
				)
				(justify mirror)
			)
		)
		(duplicate_pad_numbers_are_jumpers no)
		(fp_rect
			(start 0.2794 0.6477)
			(end -0.2794 -0.6477)
			(stroke
				(width 0)
				(type default)
			)
			(fill no)
			(layer "B.CrtYd")
		)
		(fp_rect
			(start 0.2794 0.6477)
			(end -0.2794 -0.6477)
			(stroke
				(width 0)
				(type default)
			)
			(fill no)
			(layer "B.Fab")
		)
		(pad "1" smd custom
			(at 0 -0.2794 270)
			(size 0.0762 0.0762)
			(layers "B.Cu" "B.Mask" "B.Paste")
			(net "P0V9_E")
			(options
				(clearance outline)
				(anchor circle)
			)
			(primitives
				(gr_poly
					(pts
						(arc
							(start 0.1524 0.127)
							(mid 0.137521 0.162921)
							(end 0.1016 0.1778)
						)
						(arc
							(start -0.1016 0.1778)
							(mid -0.137521 0.162921)
							(end -0.1524 0.127)
						)
						(arc
							(start -0.1524 -0.127)
							(mid -0.137521 -0.162921)
							(end -0.1016 -0.1778)
						)
						(arc
							(start 0.1016 -0.1778)
							(mid 0.137521 -0.162921)
							(end 0.1524 -0.127)
						)
					)
					(width 0)
					(fill yes)
				)
			)
		)
		(pad "2" smd custom
			(at 0 0.2794 270)
			(size 0.0762 0.0762)
			(layers "B.Cu" "B.Mask" "B.Paste")
			(net "GND")
			(options
				(clearance outline)
				(anchor circle)
			)
			(primitives
				(gr_poly
					(pts
						(arc
							(start 0.1524 0.127)
							(mid 0.137521 0.162921)
							(end 0.1016 0.1778)
						)
						(arc
							(start -0.1016 0.1778)
							(mid -0.137521 0.162921)
							(end -0.1524 0.127)
						)
						(arc
							(start -0.1524 -0.127)
							(mid -0.137521 -0.162921)
							(end -0.1016 -0.1778)
						)
						(arc
							(start 0.1016 -0.1778)
							(mid 0.137521 -0.162921)
							(end 0.1524 -0.127)
						)
					)
					(width 0)
					(fill yes)
				)
			)
		)
	)
	(footprint ""
		(layer "B.Cu")
		(at 99.7966 -98.552)
		(property "Reference" "STP164"
			(at 0 0 0)
			(layer "B.SilkS")
			(hide yes)
			(effects
				(font
					(size 1.27 1.27)
				)
				(justify mirror)
			)
		)
		(property "Value" "TPAD28"
			(at -0.0127 -1.8034 0)
			(unlocked yes)
			(layer "B.Fab")
			(hide yes)
			(effects
				(font
					(size 1.016 1.016)
					(thickness 0.1524)
				)
				(justify mirror)
			)
		)
		(property "Device Type" "TPAD28"
			(at -0.0127 -3.3274 0)
			(unlocked yes)
			(layer "B.Fab")
			(hide yes)
			(effects
				(font
					(size 1.016 1.016)
					(thickness 0.1524)
				)
				(justify mirror)
			)
		)
		(duplicate_pad_numbers_are_jumpers no)
		(fp_poly
			(pts
				(arc
					(start 0.3556 0)
					(mid -0.3556 0)
					(end 0.3556 0)
				)
			)
			(stroke
				(width 0)
				(type default)
			)
			(fill no)
			(layer "B.CrtYd")
		)
		(fp_poly
			(pts
				(arc
					(start 0.6096 0)
					(mid -0.6096 0)
					(end 0.6096 0)
				)
			)
			(stroke
				(width 0)
				(type default)
			)
			(fill no)
			(layer "B.Fab")
		)
		(pad "1" smd circle
			(at 0 0 180)
			(size 0.7112 0.7112)
			(layers "B.Cu" "B.Mask" "B.Paste")
			(net "EXP_XM_ADDR_0")
		)
	)
	(footprint ""
		(layer "B.Cu")
		(at 124.530612 -220.345 90)
		(property "Reference" "SC1288"
			(at 0 0 90)
			(layer "B.SilkS")
			(hide yes)
			(effects
				(font
					(size 1.27 1.27)
				)
				(justify mirror)
			)
		)
		(property "Value" "SC10U6D3V5KX-4GP"
			(at 0.0762 -6.1214 90)
			(unlocked yes)
			(layer "B.Fab")
			(hide yes)
			(effects
				(font
					(size 1.016 1.016)
					(thickness 0.1524)
				)
				(justify mirror)
			)
		)
		(property "Device Type" "C805H58"
			(at 0.0762 -8.1534 90)
			(unlocked yes)
			(layer "B.Fab")
			(hide yes)
			(effects
				(font
					(size 1.016 1.016)
					(thickness 0.1524)
				)
				(justify mirror)
			)
		)
		(duplicate_pad_numbers_are_jumpers no)
		(fp_line
			(start -0.635 0)
			(end 0.635 0)
			(stroke
				(width 0.508)
				(type default)
			)
			(layer "B.SilkS")
		)
		(fp_rect
			(start 0.9652 1.778)
			(end -0.9652 -1.778)
			(stroke
				(width 0)
				(type default)
			)
			(fill no)
			(layer "B.CrtYd")
		)
		(fp_poly
			(pts
				(xy 0.9652 -1.778) (xy -0.9652 -1.778) (xy -0.9652 1.778) (xy 0.9652 1.778)
			)
			(stroke
				(width 0)
				(type default)
			)
			(fill no)
			(layer "B.Fab")
		)
		(pad "1" smd rect
			(at 0 -0.9652 270)
			(size 1.397 1.143)
			(layers "B.Cu" "B.Mask" "B.Paste")
			(net "1.2V_REDV")
		)
		(pad "2" smd rect
			(at 0 0.9652 270)
			(size 1.397 1.143)
			(layers "B.Cu" "B.Mask" "B.Paste")
			(net "GND")
		)
	)
	(footprint ""
		(layer "B.Cu")
		(at 124.799852 -64.799972)
		(property "Reference" ""
			(at 0 0 0)
			(layer "B.SilkS")
			(hide yes)
			(effects
				(font
					(size 1.27 1.27)
				)
				(justify mirror)
			)
		)
		(property "Value" "*"
			(at 5.5753 -0.4572 0)
			(unlocked yes)
			(layer "B.Fab")
			(hide yes)
			(effects
				(font
					(size 1.016 1.016)
					(thickness 0.1524)
				)
				(justify mirror)
			)
		)
		(duplicate_pad_numbers_are_jumpers no)
		(fp_poly
			(pts
				(arc
					(start 4.3053 0)
					(mid -4.3053 0)
					(end 4.3053 0)
				)
			)
			(stroke
				(width 0)
				(type default)
			)
			(fill no)
			(layer "B.CrtYd")
		)
		(fp_poly
			(pts
				(arc
					(start 4.3053 0)
					(mid -4.3053 0)
					(end 4.3053 0)
				)
			)
			(stroke
				(width 0)
				(type default)
			)
			(fill no)
			(layer "B.Fab")
		)
		(pad "1" smd custom
			(at 2.95275 0 180)
			(size 2.000013 2.000013)
			(layers "B.Cu" "B.Mask" "B.Paste")
			(net "Net_48")
			(options
				(clearance outline)
				(anchor circle)
			)
			(primitives
				(gr_poly
					(pts
						(arc
							(start 4.0005 -0.00254)
							(mid -4.000501 0)
							(end 4.0005 0.00254)
						)
						(arc
							(start 1.905 0.00254)
							(mid -1.905002 0)
							(end 1.905 -0.00254)
						)
					)
					(width 0)
					(fill yes)
				)
			)
		)
	)
	(footprint ""
		(layer "B.Cu")
		(at 297.18 -180.54066)
		(property "Reference" "TP116"
			(at 0 0 0)
			(layer "B.SilkS")
			(hide yes)
			(effects
				(font
					(size 1.27 1.27)
				)
				(justify mirror)
			)
		)
		(property "Value" "TPAD28"
			(at -0.0127 -1.8034 0)
			(unlocked yes)
			(layer "B.Fab")
			(hide yes)
			(effects
				(font
					(size 1.016 1.016)
					(thickness 0.1524)
				)
				(justify mirror)
			)
		)
		(property "Device Type" "TPAD28"
			(at -0.0127 -3.3274 0)
			(unlocked yes)
			(layer "B.Fab")
			(hide yes)
			(effects
				(font
					(size 1.016 1.016)
					(thickness 0.1524)
				)
				(justify mirror)
			)
		)
		(duplicate_pad_numbers_are_jumpers no)
		(fp_poly
			(pts
				(arc
					(start 0.3556 0)
					(mid -0.3556 0)
					(end 0.3556 0)
				)
			)
			(stroke
				(width 0)
				(type default)
			)
			(fill no)
			(layer "B.CrtYd")
		)
		(fp_poly
			(pts
				(arc
					(start 0.6096 0)
					(mid -0.6096 0)
					(end 0.6096 0)
				)
			)
			(stroke
				(width 0)
				(type default)
			)
			(fill no)
			(layer "B.Fab")
		)
		(pad "1" smd circle
			(at 0 0 180)
			(size 0.7112 0.7112)
			(layers "B.Cu" "B.Mask" "B.Paste")
			(net "TP_BMC_GPIOM7")
		)
	)
)
